(kicad_pcb
	(version 20221018)
	(generator pcbnew)
	(general
    (thickness 1.562)
  )
	(paper "A4")
	(title_block
    (title "Thunderbolt PCIe Adaper")
    (date "2024-07-09")
    (rev "1.0.3")
    (comment 1 "www.antmicro.com")
    (comment 2 "Antmicro Ltd.")
		(comment 9 "footprint 10 of 271 (U4), pads 96-193 of 337")
	)
	(layers
    (0 "F.Cu" signal)
    (1 "In1.Cu" signal)
    (2 "In2.Cu" signal)
    (3 "In3.Cu" signal)
    (4 "In4.Cu" signal)
    (31 "B.Cu" signal)
    (32 "B.Adhes" user "B.Adhesive")
    (33 "F.Adhes" user "F.Adhesive")
    (34 "B.Paste" user)
    (35 "F.Paste" user)
    (36 "B.SilkS" user "B.Silkscreen")
    (37 "F.SilkS" user "F.Silkscreen")
    (38 "B.Mask" user)
    (39 "F.Mask" user)
    (40 "Dwgs.User" user "User.Drawings")
    (41 "Cmts.User" user "User.Comments")
    (42 "Eco1.User" user "User.Eco1")
    (43 "Eco2.User" user "User.Eco2")
    (44 "Edge.Cuts" user)
    (45 "Margin" user)
    (46 "B.CrtYd" user "B.Courtyard")
    (47 "F.CrtYd" user "F.Courtyard")
    (48 "B.Fab" user)
    (49 "F.Fab" user)
  )
	(footprint "antmicro-footprints:JHL6340SLLSQ"
    (layer "F.Cu")
    (at 134.8 79.85 -90)
    (property "Author" "Antmicro")
    (property "License" "Apache-2.0")
    (property "MPN" "JHL6340SLLSQ")
    (property "Manufacturer" "Intel")
    (property "Sheetfile" "tb-power.kicad_sch")
    (property "Sheetname" "Thunderbolt Controller - Power")
    (property "ki_description" "Thunderbolt™ 3 Controller, I/O")
    (property "ki_keywords" "IC")
    (attr smd)
    (fp_text reference "U4" (at -4.666 -6.17 -90 unlocked) (layer "F.SilkS")
        (effects (font (size 0.7 0.7) (thickness 0.15)))
    )
    (fp_text value "JHL6340SLLSQ" (at 0 6.4 -90 unlocked) (layer "F.Fab")
        (effects (font (size 0.7 0.7) (thickness 0.15)))
    )
    (pad "B23" smd oval (at 5.06 -4.6) (size 0.1578 0.3302) (layers "F.Cu" "F.Paste" "F.Mask")
      (net 247 "unconnected-(U4F-ATEST_N-PadB23)") (pinfunction "ATEST_N") (pintype "passive+no_connect"))
    (pad "C1" smd oval (at -5.06 -4.14) (size 0.1578 0.3302) (layers "F.Cu" "F.Paste" "F.Mask")
      (net 55 "Net-(L3-Pad1)") (pinfunction "SVR_IND") (pintype "power_out"))
    (pad "C2" smd circle (at -4.6 -4.14 270) (size 0.254 0.254) (layers "F.Cu" "F.Paste" "F.Mask")
      (net 55 "Net-(L3-Pad1)") (pinfunction "SVR_IND") (pintype "passive"))
    (pad "C22" smd circle (at 4.6 -4.14 270) (size 0.254 0.254) (layers "F.Cu" "F.Paste" "F.Mask")
      (net 1 "GND") (pinfunction "MONDC_CIO_1") (pintype "passive"))
    (pad "C23" smd oval (at 5.06 -4.14) (size 0.1578 0.3302) (layers "F.Cu" "F.Paste" "F.Mask")
      (net 1 "GND") (pinfunction "MONDC_CIO_0") (pintype "passive"))
    (pad "D1" smd oval (at -5.06 -3.68) (size 0.1578 0.3302) (layers "F.Cu" "F.Paste" "F.Mask")
      (net 55 "Net-(L3-Pad1)") (pinfunction "SVR_IND") (pintype "passive"))
    (pad "D2" smd circle (at -4.6 -3.68 270) (size 0.254 0.254) (layers "F.Cu" "F.Paste" "F.Mask")
      (net 201 "Net-(U4C-POC_GPIO_5)") (pinfunction "POC_GPIO_5") (pintype "bidirectional"))
    (pad "D4" smd circle (at -3.9 -3.9 270) (size 0.254 0.254) (layers "F.Cu" "F.Paste" "F.Mask")
      (net 199 "Net-(U4C-POC_GPIO_2)") (pinfunction "POC_GPIO_2") (pintype "bidirectional"))
    (pad "D5" smd circle (at -3.25 -3.9 270) (size 0.254 0.254) (layers "F.Cu" "F.Paste" "F.Mask")
      (net 1 "GND") (pinfunction "VSS") (pintype "passive"))
    (pad "D6" smd circle (at -2.6 -3.9 270) (size 0.254 0.254) (layers "F.Cu" "F.Paste" "F.Mask")
      (net 1 "GND") (pinfunction "MONDC_SVR") (pintype "passive"))
    (pad "D8" smd circle (at -1.95 -3.9 270) (size 0.254 0.254) (layers "F.Cu" "F.Paste" "F.Mask")
      (net 1 "GND") (pinfunction "VSS_ANA") (pintype "passive"))
    (pad "D9" smd circle (at -1.3 -3.9 270) (size 0.254 0.254) (layers "F.Cu" "F.Paste" "F.Mask")
      (net 1 "GND") (pinfunction "VSS_ANA") (pintype "passive"))
    (pad "D11" smd circle (at -0.65 -3.9 270) (size 0.254 0.254) (layers "F.Cu" "F.Paste" "F.Mask")
      (net 1 "GND") (pinfunction "VSS_ANA") (pintype "passive"))
    (pad "D12" smd circle (at 0 -3.9 270) (size 0.254 0.254) (layers "F.Cu" "F.Paste" "F.Mask")
      (net 1 "GND") (pinfunction "VSS_ANA") (pintype "passive"))
    (pad "D13" smd circle (at 0.65 -3.9 270) (size 0.254 0.254) (layers "F.Cu" "F.Paste" "F.Mask")
      (net 1 "GND") (pinfunction "VSS_ANA") (pintype "passive"))
    (pad "D15" smd circle (at 1.3 -3.9 270) (size 0.254 0.254) (layers "F.Cu" "F.Paste" "F.Mask")
      (net 1 "GND") (pinfunction "VSS_ANA") (pintype "passive"))
    (pad "D16" smd circle (at 1.95 -3.9 270) (size 0.254 0.254) (layers "F.Cu" "F.Paste" "F.Mask")
      (net 1 "GND") (pinfunction "VSS_ANA") (pintype "passive"))
    (pad "D18" smd circle (at 2.6 -3.9 270) (size 0.254 0.254) (layers "F.Cu" "F.Paste" "F.Mask")
      (net 1 "GND") (pinfunction "VSS_ANA") (pintype "passive"))
    (pad "D19" smd circle (at 3.25 -3.9 270) (size 0.254 0.254) (layers "F.Cu" "F.Paste" "F.Mask")
      (net 248 "unconnected-(U4E-PB_USB2_D_N-PadD19)") (pinfunction "PB_USB2_D_N") (pintype "bidirectional+no_connect"))
    (pad "D20" smd circle (at 3.9 -3.9 270) (size 0.254 0.254) (layers "F.Cu" "F.Paste" "F.Mask")
      (net 70 "USB_RP_N") (pinfunction "PA_USB2_D_N") (pintype "bidirectional"))
    (pad "D22" smd circle (at 4.6 -3.68 270) (size 0.254 0.254) (layers "F.Cu" "F.Paste" "F.Mask")
      (net 117 "Net-(U4D-XTAL_25_IN)") (pinfunction "XTAL_25_IN") (pintype "input"))
    (pad "D23" smd oval (at 5.06 -3.68) (size 0.1578 0.3302) (layers "F.Cu" "F.Paste" "F.Mask")
      (net 118 "Net-(U4D-XTAL_25_OUT)") (pinfunction "XTAL_25_OUT") (pintype "input"))
    (pad "E1" smd oval (at -5.06 -3.22) (size 0.1578 0.3302) (layers "F.Cu" "F.Paste" "F.Mask")
      (net 203 "Net-(U4D-TEST_EN)") (pinfunction "TEST_EN") (pintype "input"))
    (pad "E2" smd circle (at -4.6 -3.22 270) (size 0.254 0.254) (layers "F.Cu" "F.Paste" "F.Mask")
      (net 198 "Net-(U4C-POC_GPIO_1)") (pinfunction "POC_GPIO_1") (pintype "bidirectional"))
    (pad "E4" smd circle (at -3.9 -3.25 270) (size 0.254 0.254) (layers "F.Cu" "F.Paste" "F.Mask")
      (net 1 "GND") (pinfunction "VSS") (pintype "passive"))
    (pad "E5" smd circle (at -3.25 -3.25 270) (size 0.254 0.254) (layers "F.Cu" "F.Paste" "F.Mask")
      (net 1 "GND") (pinfunction "VSS") (pintype "passive"))
    (pad "E6" smd circle (at -2.6 -3.25 270) (size 0.254 0.254) (layers "F.Cu" "F.Paste" "F.Mask")
      (net 1 "GND") (pinfunction "VSS") (pintype "passive"))
    (pad "E8" smd circle (at -1.95 -3.25 270) (size 0.254 0.254) (layers "F.Cu" "F.Paste" "F.Mask")
      (net 1 "GND") (pinfunction "VSS_ANA") (pintype "passive"))
    (pad "E9" smd circle (at -1.3 -3.25 270) (size 0.254 0.254) (layers "F.Cu" "F.Paste" "F.Mask")
      (net 1 "GND") (pinfunction "VSS_ANA") (pintype "passive"))
    (pad "E11" smd circle (at -0.65 -3.25 270) (size 0.254 0.254) (layers "F.Cu" "F.Paste" "F.Mask")
      (net 1 "GND") (pinfunction "VSS_ANA") (pintype "passive"))
    (pad "E12" smd circle (at 0 -3.25 270) (size 0.254 0.254) (layers "F.Cu" "F.Paste" "F.Mask")
      (net 112 "Net-(U4A-VCC0P9_SVR_SENSE)") (pinfunction "VCC0P9_SVR_ANA") (pintype "power_in"))
    (pad "E13" smd circle (at 0.65 -3.25 270) (size 0.254 0.254) (layers "F.Cu" "F.Paste" "F.Mask")
      (net 112 "Net-(U4A-VCC0P9_SVR_SENSE)") (pinfunction "VCC0P9_SVR_ANA") (pintype "passive"))
    (pad "E15" smd circle (at 1.3 -3.25 270) (size 0.254 0.254) (layers "F.Cu" "F.Paste" "F.Mask")
      (net 1 "GND") (pinfunction "VSS_ANA") (pintype "passive"))
    (pad "E16" smd circle (at 1.95 -3.25 270) (size 0.254 0.254) (layers "F.Cu" "F.Paste" "F.Mask")
      (net 1 "GND") (pinfunction "VSS_ANA") (pintype "passive"))
    (pad "E18" smd circle (at 2.6 -3.25 270) (size 0.254 0.254) (layers "F.Cu" "F.Paste" "F.Mask")
      (net 249 "unconnected-(U4F-USB2_ATEST-PadE18)") (pinfunction "USB2_ATEST") (pintype "passive+no_connect"))
    (pad "E19" smd circle (at 3.25 -3.25 270) (size 0.254 0.254) (layers "F.Cu" "F.Paste" "F.Mask")
      (net 250 "unconnected-(U4E-PB_USB2_D_P-PadE19)") (pinfunction "PB_USB2_D_P") (pintype "bidirectional+no_connect"))
    (pad "E20" smd circle (at 3.9 -3.25 270) (size 0.254 0.254) (layers "F.Cu" "F.Paste" "F.Mask")
      (net 71 "USB_RP_P") (pinfunction "PA_USB2_D_P") (pintype "bidirectional"))
    (pad "E22" smd circle (at 4.6 -3.22 270) (size 0.254 0.254) (layers "F.Cu" "F.Paste" "F.Mask")
      (net 1 "GND") (pinfunction "VSS_ANA") (pintype "passive"))
    (pad "E23" smd oval (at 5.06 -3.22) (size 0.1578 0.3302) (layers "F.Cu" "F.Paste" "F.Mask")
      (net 1 "GND") (pinfunction "VSS_ANA") (pintype "passive"))
    (pad "F1" smd oval (at -5.06 -2.76) (size 0.1578 0.3302) (layers "F.Cu" "F.Paste" "F.Mask")
      (net 202 "Net-(U4C-POC_GPIO_6)") (pinfunction "POC_GPIO_6") (pintype "bidirectional"))
    (pad "F2" smd circle (at -4.6 -2.76 270) (size 0.254 0.254) (layers "F.Cu" "F.Paste" "F.Mask")
      (net 54 "PCIE_WAKE") (pinfunction "POC_GPIO_4") (pintype "bidirectional"))
    (pad "F4" smd circle (at -3.9 -2.6 270) (size 0.254 0.254) (layers "F.Cu" "F.Paste" "F.Mask")
      (net 62 "RESET_N") (pinfunction "RESET_N") (pintype "input"))
    (pad "F5" smd circle (at -3.25 -2.6 270) (size 0.254 0.254) (layers "F.Cu" "F.Paste" "F.Mask")
      (net 1 "GND") (pinfunction "VSS") (pintype "passive"))
    (pad "F6" smd circle (at -2.6 -2.6 270) (size 0.254 0.254) (layers "F.Cu" "F.Paste" "F.Mask")
      (net 1 "GND") (pinfunction "VSS") (pintype "passive"))
    (pad "F8" smd circle (at -1.95 -2.6 270) (size 0.254 0.254) (layers "F.Cu" "F.Paste" "F.Mask")
      (net 2 "3V3_SYS") (pinfunction "VCC3P3_SX") (pintype "power_in"))
    (pad "F9" smd circle (at -1.3 -2.6 270) (size 0.254 0.254) (layers "F.Cu" "F.Paste" "F.Mask")
      (net 1 "GND") (pinfunction "VSS_ANA") (pintype "passive"))
    (pad "F11" smd circle (at -0.65 -2.6 270) (size 0.254 0.254) (layers "F.Cu" "F.Paste" "F.Mask")
      (net 112 "Net-(U4A-VCC0P9_SVR_SENSE)") (pinfunction "VCC0P9_SVR_ANA") (pintype "passive"))
    (pad "F12" smd circle (at 0 -2.6 270) (size 0.254 0.254) (layers "F.Cu" "F.Paste" "F.Mask")
      (net 112 "Net-(U4A-VCC0P9_SVR_SENSE)") (pinfunction "VCC0P9_SVR_ANA") (pintype "passive"))
    (pad "F13" smd circle (at 0.65 -2.6 270) (size 0.254 0.254) (layers "F.Cu" "F.Paste" "F.Mask")
      (net 112 "Net-(U4A-VCC0P9_SVR_SENSE)") (pinfunction "VCC0P9_SVR_ANA") (pintype "passive"))
    (pad "F15" smd circle (at 1.3 -2.6 270) (size 0.254 0.254) (layers "F.Cu" "F.Paste" "F.Mask")
      (net 112 "Net-(U4A-VCC0P9_SVR_SENSE)") (pinfunction "VCC0P9_SVR_ANA") (pintype "passive"))
    (pad "F16" smd circle (at 1.95 -2.6 270) (size 0.254 0.254) (layers "F.Cu" "F.Paste" "F.Mask")
      (net 1 "GND") (pinfunction "VSS_ANA") (pintype "passive"))
    (pad "F18" smd circle (at 2.6 -2.6 270) (size 0.254 0.254) (layers "F.Cu" "F.Paste" "F.Mask")
      (net 113 "Net-(U4A-VCC0P9_LVR_SENSE)") (pinfunction "VCC0P9_LVR") (pintype "power_in"))
    (pad "F19" smd circle (at 3.25 -2.6 270) (size 0.254 0.254) (layers "F.Cu" "F.Paste" "F.Mask")
      (net 188 "Net-(U4E-PB_USB2_RBIAS)") (pinfunction "PB_USB2_RBIAS") (pintype "passive"))
    (pad "F20" smd circle (at 3.9 -2.6 270) (size 0.254 0.254) (layers "F.Cu" "F.Paste" "F.Mask")
      (net 1 "GND") (pinfunction "VSS_ANA") (pintype "passive"))
    (pad "F22" smd circle (at 4.6 -2.76 270) (size 0.254 0.254) (layers "F.Cu" "F.Paste" "F.Mask")
      (net 79 "/TB Controller/TX3_N") (pinfunction "PCIE_TX3_N") (pintype "input"))
    (pad "F23" smd oval (at 5.06 -2.76) (size 0.1578 0.3302) (layers "F.Cu" "F.Paste" "F.Mask")
      (net 83 "/TB Controller/TX3_P") (pinfunction "PCIE_TX3_P") (pintype "input"))
    (pad "G1" smd oval (at -5.06 -2.3) (size 0.1578 0.3302) (layers "F.Cu" "F.Paste" "F.Mask")
      (net 190 "Net-(U4C-DPSRC_HPD)") (pinfunction "DPSRC_HPD") (pintype "passive"))
    (pad "G2" smd circle (at -4.6 -2.3 270) (size 0.254 0.254) (layers "F.Cu" "F.Paste" "F.Mask")
      (net 187 "Net-(U4E-PB_DPSRC_HPD)") (pinfunction "PB_DPSRC_HPD") (pintype "input"))
    (pad "G22" smd circle (at 4.6 -2.3 270) (size 0.254 0.254) (layers "F.Cu" "F.Paste" "F.Mask")
      (net 1 "GND") (pinfunction "VSS_ANA") (pintype "passive"))
    (pad "G23" smd oval (at 5.06 -2.3) (size 0.1578 0.3302) (layers "F.Cu" "F.Paste" "F.Mask")
      (net 1 "GND") (pinfunction "VSS_ANA") (pintype "passive"))
    (pad "H1" smd oval (at -5.06 -1.84) (size 0.1578 0.3302) (layers "F.Cu" "F.Paste" "F.Mask")
      (net 1 "GND") (pinfunction "VSS_ANA") (pintype "passive"))
    (pad "H2" smd circle (at -4.6 -1.84 270) (size 0.254 0.254) (layers "F.Cu" "F.Paste" "F.Mask")
      (net 1 "GND") (pinfunction "VSS_ANA") (pintype "passive"))
    (pad "H4" smd circle (at -3.9 -1.95 270) (size 0.254 0.254) (layers "F.Cu" "F.Paste" "F.Mask")
      (net 200 "Net-(U4C-POC_GPIO_3)") (pinfunction "POC_GPIO_3") (pintype "bidirectional"))
    (pad "H5" smd circle (at -3.25 -1.95 270) (size 0.254 0.254) (layers "F.Cu" "F.Paste" "F.Mask")
      (net 1 "GND") (pinfunction "VSS") (pintype "passive"))
    (pad "H6" smd circle (at -2.6 -1.95 270) (size 0.254 0.254) (layers "F.Cu" "F.Paste" "F.Mask")
      (net 184 "Net-(U4D-RBIAS)") (pinfunction "RBIAS") (pintype "passive"))
    (pad "H8" smd circle (at -1.95 -1.95 270) (size 0.254 0.254) (layers "F.Cu" "F.Paste" "F.Mask")
      (net 1 "GND") (pinfunction "VSS") (pintype "passive"))
    (pad "H9" smd circle (at -1.3 -1.95 270) (size 0.254 0.254) (layers "F.Cu" "F.Paste" "F.Mask")
      (net 2 "3V3_SYS") (pinfunction "VCC3P3A") (pintype "power_in"))
    (pad "H11" smd circle (at -0.65 -1.95 270) (size 0.254 0.254) (layers "F.Cu" "F.Paste" "F.Mask")
      (net 113 "Net-(U4A-VCC0P9_LVR_SENSE)") (pinfunction "VCC0P9_LVR_SENSE") (pintype "power_in"))
    (pad "H12" smd circle (at 0 -1.95 270) (size 0.254 0.254) (layers "F.Cu" "F.Paste" "F.Mask")
      (net 1 "GND") (pinfunction "VSS_ANA") (pintype "passive"))
    (pad "H13" smd circle (at 0.65 -1.95 270) (size 0.254 0.254) (layers "F.Cu" "F.Paste" "F.Mask")
      (net 1 "GND") (pinfunction "VSS_ANA") (pintype "passive"))
    (pad "H15" smd circle (at 1.3 -1.95 270) (size 0.254 0.254) (layers "F.Cu" "F.Paste" "F.Mask")
      (net 1 "GND") (pinfunction "VSS_ANA") (pintype "passive"))
    (pad "H16" smd circle (at 1.95 -1.95 270) (size 0.254 0.254) (layers "F.Cu" "F.Paste" "F.Mask")
      (net 1 "GND") (pinfunction "VSS_ANA") (pintype "passive"))
    (pad "H18" smd circle (at 2.6 -1.95 270) (size 0.254 0.254) (layers "F.Cu" "F.Paste" "F.Mask")
      (net 113 "Net-(U4A-VCC0P9_LVR_SENSE)") (pinfunction "VCC0P9_LVR") (pintype "passive"))
    (pad "H19" smd circle (at 3.25 -1.95 270) (size 0.254 0.254) (layers "F.Cu" "F.Paste" "F.Mask")
      (net 182 "Net-(U4E-PA_USB2_RBIAS)") (pinfunction "PA_USB2_RBIAS") (pintype "passive"))
    (pad "H20" smd circle (at 3.9 -1.95 270) (size 0.254 0.254) (layers "F.Cu" "F.Paste" "F.Mask")
      (net 1 "GND") (pinfunction "VSS_ANA") (pintype "passive"))
    (pad "H22" smd circle (at 4.6 -1.84 270) (size 0.254 0.254) (layers "F.Cu" "F.Paste" "F.Mask")
      (net 53 "PCIE_RX3_N") (pinfunction "PCIE_RX3_N") (pintype "input"))
    (pad "H23" smd oval (at 5.06 -1.84) (size 0.1578 0.3302) (layers "F.Cu" "F.Paste" "F.Mask")
      (net 52 "PCIE_RX3_P") (pinfunction "PCIE_RX3_P") (pintype "input"))
    (pad "J1" smd oval (at -5.06 -1.38) (size 0.1578 0.3302) (layers "F.Cu" "F.Paste" "F.Mask")
      (net 251 "unconnected-(U4C-DPSRC_ML3_N-PadJ1)") (pinfunction "DPSRC_ML3_N") (pintype "output+no_connect"))
    (pad "J2" smd circle (at -4.6 -1.38 270) (size 0.254 0.254) (layers "F.Cu" "F.Paste" "F.Mask")
      (net 252 "unconnected-(U4C-DPSRC_ML3_P-PadJ2)") (pinfunction "DPSRC_ML3_P") (pintype "output+no_connect"))
    (pad "J4" smd circle (at -3.9 -1.3 270) (size 0.254 0.254) (layers "F.Cu" "F.Paste" "F.Mask")
      (net 56 "I2C1_IRQ") (pinfunction "POC_GPIO_0") (pintype "bidirectional"))
    (pad "J5" smd circle (at -3.25 -1.3 270) (size 0.254 0.254) (layers "F.Cu" "F.Paste" "F.Mask")
      (net 1 "GND") (pinfunction "VSS_ANA") (pintype "passive"))
    (pad "J6" smd circle (at -2.6 -1.3 270) (size 0.254 0.254) (layers "F.Cu" "F.Paste" "F.Mask")
      (net 183 "Net-(U4D-RSENSE)") (pinfunction "RSENSE") (pintype "passive"))
    (pad "J8" smd circle (at -1.95 -1.3 270) (size 0.254 0.254) (layers "F.Cu" "F.Paste" "F.Mask")
      (net 1 "GND") (pinfunction "VSS") (pintype "passive"))
    (pad "J9" smd circle (at -1.3 -1.3 270) (size 0.254 0.254) (layers "F.Cu" "F.Paste" "F.Mask")
      (net 112 "Net-(U4A-VCC0P9_SVR_SENSE)") (pinfunction "VCC0P9_SVR_SENSE") (pintype "power_in"))
    (pad "J11" smd circle (at -0.65 -1.3 270) (size 0.254 0.254) (layers "F.Cu" "F.Paste" "F.Mask")
      (net 113 "Net-(U4A-VCC0P9_LVR_SENSE)") (pinfunction "VCC0P9_LVR") (pintype "passive"))
    (pad "J12" smd circle (at 0 -1.3 270) (size 0.254 0.254) (layers "F.Cu" "F.Paste" "F.Mask")
      (net 1 "GND") (pinfunction "VSS") (pintype "passive"))
    (pad "J13" smd circle (at 0.65 -1.3 270) (size 0.254 0.254) (layers "F.Cu" "F.Paste" "F.Mask")
      (net 1 "GND") (pinfunction "VSS") (pintype "passive"))
    (pad "J15" smd circle (at 1.3 -1.3 270) (size 0.254 0.254) (layers "F.Cu" "F.Paste" "F.Mask")
      (net 1 "GND") (pinfunction "VSS") (pintype "passive"))
    (pad "J16" smd circle (at 1.95 -1.3 270) (size 0.254 0.254) (layers "F.Cu" "F.Paste" "F.Mask")
      (net 110 "Net-(U4A-VCC3P3_ANA_USB2)") (pinfunction "VCC3P3_ANA_USB2") (pintype "power_in"))
    (pad "J18" smd circle (at 2.6 -1.3 270) (size 0.254 0.254) (layers "F.Cu" "F.Paste" "F.Mask")
      (net 1 "GND") (pinfunction "VSS_ANA") (pintype "passive"))
    (pad "J19" smd circle (at 3.25 -1.3 270) (size 0.254 0.254) (layers "F.Cu" "F.Paste" "F.Mask")
      (net 1 "GND") (pinfunction "VSS_ANA") (pintype "passive"))
    (pad "J20" smd circle (at 3.9 -1.3 270) (size 0.254 0.254) (layers "F.Cu" "F.Paste" "F.Mask")
      (net 1 "GND") (pinfunction "VSS_ANA") (pintype "passive"))
    (pad "J22" smd circle (at 4.6 -1.38 270) (size 0.254 0.254) (layers "F.Cu" "F.Paste" "F.Mask")
      (net 1 "GND") (pinfunction "VSS_ANA") (pintype "passive"))
    (pad "J23" smd oval (at 5.06 -1.38) (size 0.1578 0.3302) (layers "F.Cu" "F.Paste" "F.Mask")
      (net 1 "GND") (pinfunction "VSS_ANA") (pintype "passive"))
    (pad "K1" smd oval (at -5.06 -0.92) (size 0.1578 0.3302) (layers "F.Cu" "F.Paste" "F.Mask")
      (net 1 "GND") (pinfunction "VSS_ANA") (pintype "passive"))
    (pad "K2" smd circle (at -4.6 -0.92 270) (size 0.254 0.254) (layers "F.Cu" "F.Paste" "F.Mask")
      (net 1 "GND") (pinfunction "VSS_ANA") (pintype "passive"))
    (pad "K22" smd circle (at 4.6 -0.92 270) (size 0.254 0.254) (layers "F.Cu" "F.Paste" "F.Mask")
      (net 78 "/TB Controller/TX2_N") (pinfunction "PCIE_TX2_N") (pintype "input"))
    (pad "K23" smd oval (at 5.06 -0.92) (size 0.1578 0.3302) (layers "F.Cu" "F.Paste" "F.Mask")
      (net 82 "/TB Controller/TX2_P") (pinfunction "PCIE_TX2_P") (pintype "input"))
  )
)
